# BASEBOARD_FAB2 (Tioga Pass) — schematic netlist excerpt (pin names and nets, part order shuffled) for the footprints in the layout excerpt that follows; sources: Cadence DE-HDL packaged netlist, KiCad conversion of Wiwynn_Tioga_Pass_MB.brd

C8B10  CAP_A  22.0UF 4V 20% X6S  pkg 0603V  page 131 : A = P1V05_PCH_STBY ; B = GND
C5D7  CAP_A  22.0UF 4V 20% X6S  pkg 0603V  page 220 : A = PVDDQ_DEF ; B = GND
R7F7  RES  2.2 5% EMPTY  pkg 0402  page 231 : A = VR_PVPP_ABC_SNUB ; B = GND

(kicad_pcb
	(version 20260206)
	(generator "pcbnew")
	(generator_version "10.0")
	(general
		(thickness 1.6)
		(legacy_teardrops no)
	)
	(paper "A4")
	(title_block
		(title "Wiwynn_Tioga_Pass_MB.brd")
		(comment 1 "Tioga Pass / footprints 2072-2074 of 4770")
	)
	(layers
		(0 "F.Cu" signal "TOP")
		(4 "In1.Cu" signal "L2GND")
		(6 "In2.Cu" signal "L3")
		(8 "In3.Cu" signal "L4GND")
		(10 "In4.Cu" signal "L5")
		(12 "In5.Cu" signal "L6GND")
		(14 "In6.Cu" signal "L7VCC")
		(16 "In7.Cu" signal "L8VCC")
		(18 "In8.Cu" signal "L9GND")
		(20 "In9.Cu" signal "L10")
		(22 "In10.Cu" signal "L11GND")
		(24 "In11.Cu" signal "L12")
		(26 "In12.Cu" signal "L13GND")
		(2 "B.Cu" signal "BOTTOM")
		(9 "F.Adhes" user "F.Adhesive")
		(11 "B.Adhes" user "B.Adhesive")
		(13 "F.Paste" user "Package Geometry/Pastemask Top")
		(15 "B.Paste" user "Package Geometry/Pastemask Bottom")
		(5 "F.SilkS" user "Ref Des/Silkscreen Top")
		(7 "B.SilkS" user "Ref Des/Silkscreen Bottom")
		(1 "F.Mask" user "Board Geometry/Soldermask Top")
		(3 "B.Mask" user "Board Geometry/Soldermask Bottom")
		(17 "Dwgs.User" user "User.Drawings")
		(19 "Cmts.User" user "User.Comments")
		(21 "Eco1.User" user "User.Eco1")
		(23 "Eco2.User" user "User.Eco2")
		(25 "Edge.Cuts" user "Board Geometry/Outline")
		(27 "Margin" user)
		(31 "F.CrtYd" user "Package Geometry/Place Bound Top")
		(29 "B.CrtYd" user "Package Geometry/Place Bound Bottom")
		(35 "F.Fab" user "Ref Des/Assembly Top")
		(33 "B.Fab" user "Ref Des/Assembly Bottom")
	)
	(footprint ""
		(layer "F.Cu")
		(at 266.0142 -84.7598)
		(property "Reference" "C5D7"
			(at 0 0 0)
			(layer "F.SilkS")
			(hide yes)
			(effects
				(font
					(size 1.27 1.27)
				)
			)
		)
		(property "Value" ""
			(at 0 0 0)
			(layer "F.Fab")
			(effects
				(font
					(size 1.27 1.27)
				)
			)
		)
		(duplicate_pad_numbers_are_jumpers no)
		(fp_poly
			(pts
				(xy -0.4953 -0.2032) (xy 0.4953 -0.2032) (xy 0.4953 1.6002) (xy -0.4953 1.6002)
			)
			(stroke
				(width 0)
				(type default)
			)
			(fill no)
			(layer "F.CrtYd")
		)
		(fp_line
			(start -0.4953 -0.2032)
			(end 0.4953 -0.2032)
			(stroke
				(width 0.1)
				(type default)
			)
			(layer "F.Fab")
		)
		(fp_line
			(start -0.4953 1.6002)
			(end -0.4953 -0.2032)
			(stroke
				(width 0.1)
				(type default)
			)
			(layer "F.Fab")
		)
		(fp_line
			(start 0.4953 -0.2032)
			(end 0.4953 1.6002)
			(stroke
				(width 0.1)
				(type default)
			)
			(layer "F.Fab")
		)
		(fp_line
			(start 0.4953 1.6002)
			(end -0.4953 1.6002)
			(stroke
				(width 0.1)
				(type default)
			)
			(layer "F.Fab")
		)
		(pad "1" smd rect
			(at 0 0)
			(size 0.762 0.889)
			(layers "F.Cu" "F.Mask" "F.Paste")
			(net "PVDDQ_DEF")
		)
		(pad "2" smd rect
			(at 0 1.397)
			(size 0.762 0.889)
			(layers "F.Cu" "F.Mask" "F.Paste")
			(net "GND")
		)
		(zone
			(layer "F.Cu")
			(hatch none 0.5)
			(connect_pads
				(clearance 0)
			)
			(min_thickness 0.25)
			(keepout
				(tracks not_allowed)
				(vias allowed)
				(pads allowed)
				(copperpour not_allowed)
				(footprints allowed)
			)
			(placement
				(enabled no)
				(sheetname "")
			)
			(fill
				(thermal_gap 0.5)
				(thermal_bridge_width 0.5)
				(island_removal_mode 0)
			)
			(polygon
				(pts
					(xy 265.6332 -84.3153) (xy 266.3952 -84.3153) (xy 266.3952 -83.8073) (xy 265.6332 -83.8073)
				)
			)
		)
	)
	(footprint ""
		(layer "F.Cu")
		(at 343.9668 -32.8803 90)
		(property "Reference" "R7F7"
			(at 0 0 90)
			(layer "F.SilkS")
			(hide yes)
			(effects
				(font
					(size 1.27 1.27)
				)
			)
		)
		(property "Value" ""
			(at 0 0 90)
			(layer "F.Fab")
			(effects
				(font
					(size 1.27 1.27)
				)
			)
		)
		(duplicate_pad_numbers_are_jumpers no)
		(fp_rect
			(start -0.2794 -0.1016)
			(end 0.2794 0.9906)
			(stroke
				(width 0)
				(type default)
			)
			(fill no)
			(layer "F.CrtYd")
		)
		(fp_line
			(start 0.2794 -0.1016)
			(end -0.2794 -0.1016)
			(stroke
				(width 0.1)
				(type default)
			)
			(layer "F.Fab")
		)
		(fp_line
			(start -0.2794 -0.1016)
			(end -0.2794 0.9906)
			(stroke
				(width 0.1)
				(type default)
			)
			(layer "F.Fab")
		)
		(fp_line
			(start 0.2794 0.9906)
			(end 0.2794 -0.1016)
			(stroke
				(width 0.1)
				(type default)
			)
			(layer "F.Fab")
		)
		(fp_line
			(start -0.2794 0.9906)
			(end 0.2794 0.9906)
			(stroke
				(width 0.1)
				(type default)
			)
			(layer "F.Fab")
		)
		(pad "1" smd rect
			(at 0 0 90)
			(size 0.508 0.508)
			(layers "F.Cu" "F.Mask" "F.Paste")
			(net "VR_PVPP_ABC_SNUB")
		)
		(pad "2" smd rect
			(at 0 0.889 90)
			(size 0.508 0.508)
			(layers "F.Cu" "F.Mask" "F.Paste")
			(net "GND")
		)
		(zone
			(layer "F.Cu")
			(hatch none 0.5)
			(connect_pads
				(clearance 0)
			)
			(min_thickness 0.25)
			(keepout
				(tracks not_allowed)
				(vias allowed)
				(pads allowed)
				(copperpour not_allowed)
				(footprints allowed)
			)
			(placement
				(enabled no)
				(sheetname "")
			)
			(fill
				(thermal_gap 0.5)
				(thermal_bridge_width 0.5)
				(island_removal_mode 0)
			)
			(polygon
				(pts
					(xy 344.2208 -32.6263) (xy 344.6018 -32.6263) (xy 344.6018 -33.1343) (xy 344.2208 -33.1343)
				)
			)
		)
		(zone
			(layer "F.Cu")
			(hatch none 0.5)
			(connect_pads
				(clearance 0)
			)
			(min_thickness 0.25)
			(keepout
				(tracks allowed)
				(vias not_allowed)
				(pads allowed)
				(copperpour not_allowed)
				(footprints allowed)
			)
			(placement
				(enabled no)
				(sheetname "")
			)
			(fill
				(thermal_gap 0.5)
				(thermal_bridge_width 0.5)
				(island_removal_mode 0)
			)
			(polygon
				(pts
					(xy 344.2208 -32.6263) (xy 344.6018 -32.6263) (xy 344.6018 -33.1343) (xy 344.2208 -33.1343)
				)
			)
		)
	)
	(footprint ""
		(layer "F.Cu")
		(at 409.448 -126.238)
		(property "Reference" "C8B10"
			(at 0 0 0)
			(layer "F.SilkS")
			(hide yes)
			(effects
				(font
					(size 1.27 1.27)
				)
			)
		)
		(property "Value" ""
			(at 0 0 0)
			(layer "F.Fab")
			(effects
				(font
					(size 1.27 1.27)
				)
			)
		)
		(duplicate_pad_numbers_are_jumpers no)
		(fp_poly
			(pts
				(xy -0.4953 -0.2032) (xy 0.4953 -0.2032) (xy 0.4953 1.6002) (xy -0.4953 1.6002)
			)
			(stroke
				(width 0)
				(type default)
			)
			(fill no)
			(layer "F.CrtYd")
		)
		(fp_line
			(start -0.4953 -0.2032)
			(end 0.4953 -0.2032)
			(stroke
				(width 0.1)
				(type default)
			)
			(layer "F.Fab")
		)
		(fp_line
			(start -0.4953 1.6002)
			(end -0.4953 -0.2032)
			(stroke
				(width 0.1)
				(type default)
			)
			(layer "F.Fab")
		)
		(fp_line
			(start 0.4953 -0.2032)
			(end 0.4953 1.6002)
			(stroke
				(width 0.1)
				(type default)
			)
			(layer "F.Fab")
		)
		(fp_line
			(start 0.4953 1.6002)
			(end -0.4953 1.6002)
			(stroke
				(width 0.1)
				(type default)
			)
			(layer "F.Fab")
		)
		(pad "1" smd rect
			(at 0 0)
			(size 0.762 0.889)
			(layers "F.Cu" "F.Mask" "F.Paste")
			(net "P1V05_PCH_STBY")
		)
		(pad "2" smd rect
			(at 0 1.397)
			(size 0.762 0.889)
			(layers "F.Cu" "F.Mask" "F.Paste")
			(net "GND")
		)
		(zone
			(layer "F.Cu")
			(hatch none 0.5)
			(connect_pads
				(clearance 0)
			)
			(min_thickness 0.25)
			(keepout
				(tracks not_allowed)
				(vias allowed)
				(pads allowed)
				(copperpour not_allowed)
				(footprints allowed)
			)
			(placement
				(enabled no)
				(sheetname "")
			)
			(fill
				(thermal_gap 0.5)
				(thermal_bridge_width 0.5)
				(island_removal_mode 0)
			)
			(polygon
				(pts
					(xy 409.067 -125.7935) (xy 409.829 -125.7935) (xy 409.829 -125.2855) (xy 409.067 -125.2855)
				)
			)
		)
	)
)
